FILE_TYPE = MACRO_DRAWING;
SET COLOR_WIRE YELLOW;
SET COLOR_PROP ORANGE;
SET COLOR_DOT WHITE;
SET COLOR_ARC YELLOW;
SET COLOR_BODY GREEN;
SET COLOR_NOTE PURPLE;
SET PROP_DISPLAY VALUE;
SET PAGE_NUMBER P3;
SET PATH_NUMBER P0;
FORCEADD QUANTA_TITLE_BLOCK_C..1
(3650 -1400);
FORCEPROP 0 LAST CDS_CON_LAST_MODIFIED Fri Aug 25 17:25:34 2023
J 0
(1765 -1385);
DISPLAY INVISIBLE (1765 -1385);
FORCEPROP 2 LAST Q_DEPT 
J 1
(-113 -1351);
DISPLAY 1.957447 (-113 -1351);
PAINT GREEN (-113 -1351);
FORCEPROP 1 LAST CUSTOM_TXT_CDS <CON_LAST_MODIFIED>
J 0
(1765 -1385);
DISPLAY 0.978723 (1765 -1385);
FORCEPROP 2 LAST CUSTOM_TXT_CDS <XR_PAGE_TITLE>
J 0
(-4240 3850);
DISPLAY 0.638298 (-4240 3850);
PAINT PINK (-4240 3850);
DISPLAY INVISIBLE (-4240 3850);
FORCEPROP 1 LAST CUSTOM_TXT_CDS <NAME_2>
J 0
(475 -1350);
FORCEPROP 1 LAST CUSTOM_TXT_CDS <NAME_1>
J 0
(475 -1225);
FORCEPROP 1 LAST CUSTOM_TXT_CDS <Q_NUMBER>
J 0
(2247 -1297);
DISPLAY 1.212766 (2247 -1297);
FORCEPROP 1 LAST CUSTOM_TXT_CDS <Q_PROJ>
J 0
(1268 -1298);
DISPLAY 1.212766 (1268 -1298);
FORCEPROP 1 LAST CUSTOM_TXT_CDS <Q_REV>
J 0
(3466 -1297);
DISPLAY 1.212766 (3466 -1297);
FORCEPROP 1 LAST CUSTOM_TXT_CDS <CON_PAGE_NUM> OF <CON_TOTAL_PAGES>
J 0
(3204 -1382);
DISPLAY 0.978723 (3204 -1382);
FORCEPROP 1 LAST Q_TITLE BLOCK DIAGRAM
J 0
(-5716 -1374);
DISPLAY 2.446809 (-5716 -1374);
PAINT GREEN (-5716 -1374);
FORCEPROP 2 LAST CDS_LIB pure_quanta
J 0
(3650 -1400);
DISPLAY INVISIBLE (3650 -1400);
FORCEPROP 1 LAST CDS_LMAN_SYM_OUTLINE -9475,6775,100,-125
J 0
(3650 -1400);
DISPLAY 0.468085 (3650 -1400);
PAINT GREEN (3650 -1400);
DISPLAY INVISIBLE (3650 -1400);
FORCEPROP 2 LAST PAGE_BORDER TRUE
J 0
(-4240 3850);
DISPLAY 0.638298 (-4240 3850);
PAINT PINK (-4240 3850);
DISPLAY INVISIBLE (-4240 3850);
FORCEPROP 1 LAST COMMENT_BODY TRUE
J 0
(3662 -1413);
DISPLAY 0.978723 (3662 -1413);
PAINT PEACH (3662 -1413);
DISPLAY INVISIBLE (3662 -1413);
FORCEPROP 2 LAST CDS_XR_PAGE_TITLE CR-3 : @SCM_LIB.SCM(SCH_1):PAGE3
J 0
(-4240 3850);
DISPLAY 0.638298 (-4240 3850);
PAINT PINK (-4240 3850);
DISPLAY INVISIBLE (-4240 3850);
FORCENOTE
$CDS_IMAGE|F0T_SCM_Block_Diagram_20220818-SCM.jpg|7645|6175
(-1175 2025) 0;
DISPLAY LEFT (-1175 2025);
QUIT
